FILE_TYPE = MULTI_PHYS_TABLE;

PART 'Q_INDUCTOR4P_14'

{========================================================================================}
:VALUE                 | PART_TYPE | MATERIAL | PART_NUMBER       = STANDARD        | LIFECYCLE      | PART_NUMBER       | JEDEC_TYPE                    | CURRENT | DESCRIPTION                                | MANUFTR | MANUF_PN               | RD_CMPLS_LVL | CMPLS_LVL | CLASS      | DIP_SMD | FROM_PJ       | DATA                           | FP_ECN            | EE_CHECK_LIST     | STATUS | PREFERENCE | NOT_INSERT | DAY        ;
{========================================================================================}
 'SMB-665025'          | 'SMLF'    | 'IND'    | 'CX665025001'(!)  = ''              | ''             | 'CX665025001'     |'L_SMB665025'| '10A'   | 'EMI FILTER SMB-665025(33OHM,10A)'         | 'MAG'   | 'SMB-665025'           | ''           | 'EP'      | 'DISCRETE' | ''      | 'A05-DEMON'   | 'MAG_SMB-665025.pdf'           | 'L_SMB665025.DOC' | 'L_SMB665025.xls' | ''     | ''         | ''         | '20110222'
 'SMB-665025'          | 'SMLF'    | 'EMPTY'  | 'CX665025001'(!)  = ''              | ''             | 'CX665025001'     |'L_SMB665025'| '10A'   | 'EMI FILTER SMB-665025(33OHM,10A)'         | 'MAG'   | 'SMB-665025'           | ''           | 'EP'      | 'DISCRETE' | ''      | 'A05-DEMON'   | 'MAG_SMB-665025.pdf'           | 'L_SMB665025.DOC' | 'L_SMB665025.xls' | ''     | ''         | ''         | '20110222'
 'ACM2012-201-2P-T'    | 'SMLF'    | 'IND'    | 'CXCM2012001'(!)  = ''              | ''             | 'CXCM2012001'     |'L_ACM2012'| '350MA' | 'EMI FILTER ACM2012-201-2P-T(50V,350MA)'   | 'TDK'   | 'ACM2012-201-2P-T'     | ''           | 'EP_Tmp'  | 'DISCRETE' | ''      | 'A06-EDISON'  | 'TDK_ACM-SERIES.pdf'           | ''                | 'L_ACM2012.xls'   | ''     | ''         | ''         | '20110222'
 'ACM2012-201-2P-T'    | 'SMLF'    | 'EMPTY'  | 'CXCM2012001'(!)  = ''              | ''             | 'CXCM2012001'     |'L_ACM2012'| '350MA' | 'EMI FILTER ACM2012-201-2P-T(50V,350MA)'   | 'TDK'   | 'ACM2012-201-2P-T'     | ''           | 'EP_Tmp'  | 'DISCRETE' | ''      | 'A06-EDISON'  | 'TDK_ACM-SERIES.pdf'           | ''                | 'L_ACM2012.xls'   | ''     | ''         | ''         | '20110222'
 'ACM2012H-900-2P-T00' | 'SMLF'    | 'IND'    | 'CX12H900001'(!)  = 'End of Design' | 'End of Life'  | 'CX12H900001'     |'L_ACM2012_EOL'| '300MA' | 'EMI FILT ACM2012H-900-2P-T00(20V300MA)'   | 'TDK'   | 'ACM2012H-900-2P-T00'  | ''           | 'EP'      | 'DISCRETE' | ''      | 'S99C-MINGLI' | 'ACM2012H-900-2P-x00.pdf'      | ''                | ''                | ''     | ''         | ''         | '20110222'
 'ACM2012H-900-2P-T00' | 'SMLF'    | 'EMPTY'  | 'CX12H900001'(!)  = 'End of Design' | 'End of Life'  | 'CX12H900001'     |'L_ACM2012_EOL'| '300MA' | 'EMI FILT ACM2012H-900-2P-T00(20V300MA)'   | 'TDK'   | 'ACM2012H-900-2P-T00'  | ''           | 'EP'      | 'DISCRETE' | ''      | 'S99C-MINGLI' | 'ACM2012H-900-2P-x00.pdf'      | ''                | ''                | ''     | ''         | ''         | '20110222'
 '20V/200MA'           | 'SMLF'    | 'IND'    | 'CXCM2012002'(!)  = 'End of Design' | 'Comp-Approve' | 'CXCM2012002'     |'L_ACM2012XA'| '200MA' | 'EMI FILTER ACM2012-900-2P-T(20V,200MA)EP' | 'TDK'   | 'ACM2012-900-2P-T'     | 'EP'         | 'EP'      | 'DISCRETE' | ''      | 'JB9-JACK'    | 'ACM2012E-series_rev2011.pdf'  | ''                | ''                | ''     | ''         | ''         | '20120525'
 '20V/200MA'           | 'SMLF'    | 'EMPTY'  | 'CXCM2012002'(!)  = 'End of Design' | 'Comp-Approve' | 'CXCM2012002'     |'L_ACM2012XA'| '200MA' | 'EMI FILTER ACM2012-900-2P-T(20V,200MA)EP' | 'TDK'   | 'ACM2012-900-2P-T'     | 'EP'         | 'EP'      | 'DISCRETE' | ''      | 'JB9-JACK'    | 'ACM2012E-series_rev2011.pdf'  | ''                | ''                | ''     | ''         | ''         | '20120525'
 '90/400MA'            | 'SMLF'    | 'IND'    | 'CX02012E000'(!)  = 'End of Design' | 'End of Life'  | 'CX02012E000'     |'L_ACM2012XA_EOL'| '400MA' | 'EMI FILTER ACM2012E-900-2P-T-00 90,4OOMA' | 'TDK'   | 'ACM2012E-900-2P-T-00' | 'EP(V1)'     | ''        | 'DISCRETE' | ''      | 'JB9-JACK'    | 'ACM2012E-series_rev2011.pdf'  | ''                | ''                | ''     | ''         | ''         | '20120525'
 '90/400MA'            | 'SMLF'    | 'EMPTY'  | 'CX02012E000'(!)  = 'End of Design' | 'End of Life'  | 'CX02012E000'     |'L_ACM2012XA_EOL'| '400MA' | 'EMI FILTER ACM2012E-900-2P-T-00 90,4OOMA' | 'TDK'   | 'ACM2012E-900-2P-T-00' | 'EP(V1)'     | ''        | 'DISCRETE' | ''      | 'JB9-JACK'    | 'ACM2012E-series_rev2011.pdf'  | ''                | ''                | ''     | ''         | ''         | '20120525'
 '150NH'               | 'SMLF'    | 'IND'    | 'CV+15^0TZ00'(!)  = ''              | ''             | 'CV+15^0TZ00'     |'L_VLBC12060120R10LF3_12X6XA'| '82A'   | 'IND SMD 150NH 15% 82A(VLBC12060120R15LF3' | 'TDK'   | 'VLBC12060120R15LF3'   | 'EP(V1)'     | ''        | 'DISCRETE' | ''      | 'S8Z-FRANK'   | 'TDK_VLBC12060120R15LF3.pdf'   | ''                | ''                | ''     | ''         | ''         | '20200527'
 '150NH'               | 'SMLF'    | 'EMPTY'  | 'CV+15^0TZ00'(!)  = ''              | ''             | 'CV+15^0TZ00'     |'L_VLBC12060120R10LF3_12X6XA'| '82A'   | 'IND SMD 150NH 15% 82A(VLBC12060120R15LF3' | 'TDK'   | 'VLBC12060120R15LF3'   | 'EP(V1)'     | ''        | 'DISCRETE' | ''      | 'S8Z-FRANK'   | 'TDK_VLBC12060120R15LF3.pdf'   | ''                | ''                | ''     | ''         | ''         | '20200527'
 '105NH'               | 'SMLF'    | 'IND'    | 'CV+10^0TZ02'(!)  = ''              | ''             | 'CV+10^0TZ02'     |'L_VLBC12060120R10LF3_12X6XA'| '125A'  | 'IND SMD 105NH+-15%125A(VLBC12060120R10LF' | 'TDK'   | 'VLBC12060120R10LF3'   | 'EP(V1)'     | ''        | 'DISCRETE' | ''      | 'S8Z-FRANK'   | 'TDK_VLBC12060120R10LF3.pdf'   | ''                | ''                | ''     | ''         | ''         | '20200527'
 '105NH'               | 'SMLF'    | 'EMPTY'  | 'CV+10^0TZ02'(!)  = ''              | ''             | 'CV+10^0TZ02'     |'L_VLBC12060120R10LF3_12X6XA'| '125A'  | 'IND SMD 105NH+-15%125A(VLBC12060120R10LF' | 'TDK'   | 'VLBC12060120R10LF3'   | 'EP(V1)'     | ''        | 'DISCRETE' | ''      | 'S8Z-FRANK'   | 'TDK_VLBC12060120R10LF3.pdf'   | ''                | ''                | ''     | ''         | ''         | '20200527'
 '170NH'               | 'SMLF'    | 'IND'    | 'CV+17^0EZ02'(!)  = ''              | ''             | 'CV+17^0EZ02'     |'L_VLBC12060120R10LF3_12X6XA'| '70A'   | 'IND SMD 170NH 15% 70A(VLBC12060120R17LF3' | 'TDK'   | 'VLBC12060120R17LF3'   | 'EP(V1)'     | ''        | 'DISCRETE' | ''      | 'S8Z-FRANK'   | 'TDK_VLBC12060120R17LF3.pdf'   | ''                | ''                | ''     | ''         | ''         | '20200527'
 '170NH'               | 'SMLF'    | 'EMPTY'  | 'CV+17^0EZ02'(!)  = ''              | ''             | 'CV+17^0EZ02'     |'L_VLBC12060120R10LF3_12X6XA'| '70A'   | 'IND SMD 170NH 15% 70A(VLBC12060120R17LF3' | 'TDK'   | 'VLBC12060120R17LF3'   | 'EP(V1)'     | ''        | 'DISCRETE' | ''      | 'S8Z-FRANK'   | 'TDK_VLBC12060120R17LF3.pdf'   | ''                | ''                | ''     | ''         | ''         | '20200527'
 '105NH'               | 'SMLF'    | 'IND'    | 'CV+11^0EZ00'(!)  = ''              | ''             | 'CV+11^0EZ00'     |'L_TLM1211Q-111QL_12X6'| '118A'  | 'IND SMD 105NH 15% 118A(TLM1211Q-111QL)'   | 'DTA'   | 'TLM1211Q-111QL'       | 'EP(V1)'     | ''        | 'DISCRETE' | ''      | 'S8Z-FRANK'   | 'DTA_TLM1211Q-111QL.pdf'       | ''                | ''                | ''     | ''         | ''         | '20200528'
 '105NH'               | 'SMLF'    | 'EMPTY'  | 'CV+11^0EZ00'(!)  = ''              | ''             | 'CV+11^0EZ00'     |'L_TLM1211Q-111QL_12X6'| '118A'  | 'IND SMD 105NH 15% 118A(TLM1211Q-111QL)'   | 'DTA'   | 'TLM1211Q-111QL'       | 'EP(V1)'     | ''        | 'DISCRETE' | ''      | 'S8Z-FRANK'   | 'DTA_TLM1211Q-111QL.pdf'       | ''                | ''                | ''     | ''         | ''         | '20200528'
 '150NH'               | 'SMLF'    | 'IND'    | 'CV+15^0EZ05'(!)  = ''              | ''             | 'CV+15^0EZ05'     |'L_TLM1211Q-111QL_12X6'| '84A'   | 'IND SMD 150NH 15% 84A(TLM1211Q-151QL)'    | 'DTA'   | 'TLM1211Q-151QL'       | 'EP(V1)'     | ''        | 'DISCRETE' | ''      | 'S8Z-FRANK'   | 'DTA_TLM1211Q-151QL.pdf'       | ''                | ''                | ''     | ''         | ''         | '20200528'
 '150NH'               | 'SMLF'    | 'EMPTY'  | 'CV+15^0EZ05'(!)  = ''              | ''             | 'CV+15^0EZ05'     |'L_TLM1211Q-111QL_12X6'| '84A'   | 'IND SMD 150NH 15% 84A(TLM1211Q-151QL)'    | 'DTA'   | 'TLM1211Q-151QL'       | 'EP(V1)'     | ''        | 'DISCRETE' | ''      | 'S8Z-FRANK'   | 'DTA_TLM1211Q-151QL.pdf'       | ''                | ''                | ''     | ''         | ''         | '20200528'
 '170NH'               | 'SMLF'    | 'IND'    | 'CV+17^0EZ03'(!)  = ''              | ''             | 'CV+17^0EZ03'     |'L_TLM1211Q-111QL_12X6'| '70A'   | 'IND SMD 170NH 15% 70A(TLM1211Q-171QL)'    | 'DTA'   | 'TLM1211Q-171QL'       | 'EP(V1)'     | ''        | 'DISCRETE' | ''      | 'S8Z-FRANK'   | 'DTA_TLM1211Q-171QL.pdf'       | ''                | ''                | ''     | ''         | ''         | '20200602'
 '170NH'               | 'SMLF'    | 'EMPTY'  | 'CV+17^0EZ03'(!)  = ''              | ''             | 'CV+17^0EZ03'     |'L_TLM1211Q-111QL_12X6'| '70A'   | 'IND SMD 170NH 15% 70A(TLM1211Q-171QL)'    | 'DTA'   | 'TLM1211Q-171QL'       | 'EP(V1)'     | ''        | 'DISCRETE' | ''      | 'S8Z-FRANK'   | 'DTA_TLM1211Q-171QL.pdf'       | ''                | ''                | ''     | ''         | ''         | '20200602'
 '105NH'               | 'SMLF'    | 'IND'    | 'CV+10^0EZ01'(!)  = ''              | ''             | 'CV+10^0EZ01'     |'L_VLBC12060120R10LF3_12X6XA'| '125A'  | 'IND SMD 105NH 15% 125A(VLBUC12060120R10)' | 'TDK'   | 'VLBUC12060120R10LF3'  | 'EP(V1)'     | ''        | 'DISCRETE' | ''      | 'S8Z-FRANK'   | 'TDK_VLBUC12060120R10LF3.pdf'  | ''                | ''                | ''     | ''         | ''         | '20200617'
 '105NH'               | 'SMLF'    | 'EMPTY'  | 'CV+10^0EZ01'(!)  = ''              | ''             | 'CV+10^0EZ01'     |'L_VLBC12060120R10LF3_12X6XA'| '125A'  | 'IND SMD 105NH 15% 125A(VLBUC12060120R10)' | 'TDK'   | 'VLBUC12060120R10LF3'  | 'EP(V1)'     | ''        | 'DISCRETE' | ''      | 'S8Z-FRANK'   | 'TDK_VLBUC12060120R10LF3.pdf'  | ''                | ''                | ''     | ''         | ''         | '20200617'
 '170NH'               | 'SMLF'    | 'IND'    | 'CV+17^0EZ04'(!)  = ''              | ''             | 'CV+17^0EZ04'     |'L_VLBC12060120R10LF3_12X6XA'| '70A'   | 'IND SMD 170NH 15% 70A(VLBUC12060120R17)'  | 'TDK'   | 'VLBUC12060120R17LF3'  | 'EP(V1)'     | ''        | 'DISCRETE' | ''      | 'S8Z-FRANK'   | 'TDK_VLBUC12060120R17LF3.pdf'  | ''                | ''                | ''     | ''         | ''         | '20200617'
 '170NH'               | 'SMLF'    | 'EMPTY'  | 'CV+17^0EZ04'(!)  = ''              | ''             | 'CV+17^0EZ04'     |'L_VLBC12060120R10LF3_12X6XA'| '70A'   | 'IND SMD 170NH 15% 70A(VLBUC12060120R17)'  | 'TDK'   | 'VLBUC12060120R17LF3'  | 'EP(V1)'     | ''        | 'DISCRETE' | ''      | 'S8Z-FRANK'   | 'TDK_VLBUC12060120R17LF3.pdf'  | ''                | ''                | ''     | ''         | ''         | '20200617'
 '150NH'               | 'SMLF'    | 'IND'    | 'CV+15^0EZ06'(!)  = ''              | ''             | 'CV+15^0EZ06'     |'L_VLBC12060120R10LF3_12X6XA'| '82A'   | 'IND SMD 150NH 15% 82A(VLBUC12060120R15)'  | 'TDK'   | 'VLBUC12060120R15LF3'  | 'EP(V1)'     | ''        | 'DISCRETE' | ''      | 'S8Z-FRANK'   | 'TDK_VLBUC12060120R15LF3.pdf'  | ''                | ''                | ''     | ''         | ''         | '20200617'
 '150NH'               | 'SMLF'    | 'EMPTY'  | 'CV+15^0EZ06'(!)  = ''              | ''             | 'CV+15^0EZ06'     |'L_VLBC12060120R10LF3_12X6XA'| '82A'   | 'IND SMD 150NH 15% 82A(VLBUC12060120R15)'  | 'TDK'   | 'VLBUC12060120R15LF3'  | 'EP(V1)'     | ''        | 'DISCRETE' | ''      | 'S8Z-FRANK'   | 'TDK_VLBUC12060120R15LF3.pdf'  | ''                | ''                | ''     | ''         | ''         | '20200617'
 '150NH'               | 'SMLF'    | 'IND'    | 'CV+15^0EZ09'(!)  = ''              | ''             | 'CV+15^0EZ09'     |'L_TLM117513Q-151QL_11X7-5XA'| '82A'   | 'IND SMD 150NH 15% 82A(TLM117513Q-151QL)'  | 'DTA'   | 'TLM117513Q-151QL'     | 'EP(V1)'     | ''        | 'DISCRETE' | ''      | 'S6Q-KIMI'    | 'DTA_TLM117513Q-151QL.pdf'     | ''                | ''                | ''     | ''         | ''         | '20200825'
 '150NH'               | 'SMLF'    | 'EMPTY'  | 'CV+15^0EZ09'(!)  = ''              | ''             | 'CV+15^0EZ09'     |'L_TLM117513Q-151QL_11X7-5XA'| '82A'   | 'IND SMD 150NH 15% 82A(TLM117513Q-151QL)'  | 'DTA'   | 'TLM117513Q-151QL'     | 'EP(V1)'     | ''        | 'DISCRETE' | ''      | 'S6Q-KIMI'    | 'DTA_TLM117513Q-151QL.pdf'     | ''                | ''                | ''     | ''         | ''         | '20200825'
 '150NH'               | 'SMLF'    | 'IND'    | 'CV+15^0TZ01'(!)  = ''              | ''             | 'CV+15^0TZ01'     |'L_TLM117513Q-151QL_11X7-5XA'| '82A'   | 'IND SMD 150NH 15% 82A(TLM117513Q-151AQL)' | 'DTA'   | 'TLM117513Q-151AQL'    | 'EP(V1)'     | ''        | 'DISCRETE' | ''      | 'S6Q-KIMI'    | 'DTA_TLM117513Q-151AQL.pdf'    | ''                | ''                | ''     | ''         | ''         | '20200827'
 '150NH'               | 'SMLF'    | 'EMPTY'  | 'CV+15^0TZ01'(!)  = ''              | ''             | 'CV+15^0TZ01'     |'L_TLM117513Q-151QL_11X7-5XA'| '82A'   | 'IND SMD 150NH 15% 82A(TLM117513Q-151AQL)' | 'DTA'   | 'TLM117513Q-151AQL'    | 'EP(V1)'     | ''        | 'DISCRETE' | ''      | 'S6Q-KIMI'    | 'DTA_TLM117513Q-151AQL.pdf'    | ''                | ''                | ''     | ''         | ''         | '20200827'
 '150NH'               | 'SMLF'    | 'IND'    | 'CV+15^0EZ10'(!)  = ''              | ''             | 'CV+15^0EZ10'     |'L_VLBC12060120R10LF3_12X6XA'| '82A'   | 'IND SMD 150NH 15% 82A(PGL6181.151HLT)'    | 'PLE'   | 'PGL6181.151HLT'       | 'EP(V1)'     | ''        | 'DISCRETE' | ''      | 'S8Z-BRIAN'   | 'PLE_PGL6181.151HLT.pdf'       | ''                | ''                | ''     | ''         | ''         | '20201012'
 '150NH'               | 'SMLF'    | 'EMPTY'  | 'CV+15^0EZ10'(!)  = ''              | ''             | 'CV+15^0EZ10'     |'L_VLBC12060120R10LF3_12X6XA'| '82A'   | 'IND SMD 150NH 15% 82A(PGL6181.151HLT)'    | 'PLE'   | 'PGL6181.151HLT'       | 'EP(V1)'     | ''        | 'DISCRETE' | ''      | 'S8Z-BRIAN'   | 'PLE_PGL6181.151HLT.pdf'       | ''                | ''                | ''     | ''         | ''         | '20201012'
 '150NH'               | 'SMLF'    | 'IND'    | 'CV+15^0TZ04'(!)  = 'End of Design' | 'Comp-Approve' | 'CV+15^0TZ04'     |'L_TLM117513Q-151QL_11X7-5XA'| '82A'   | 'IND SMD 150NH 15% 82A(PGL6303.151HLT)'    | 'PLE'   | 'PGL6303.151HLT'       | 'EP(V1)'     | ''        | 'DISCRETE' | ''      | 'S6X-KIMI'    | 'PLE_PGL6303.151HLT.pdf'       | ''                | ''                | ''     | ''         | ''         | '20201026'
 '150NH'               | 'SMLF'    | 'EMPTY'  | 'CV+15^0TZ04'(!)  = 'End of Design' | 'Comp-Approve' | 'CV+15^0TZ04'     |'L_TLM117513Q-151QL_11X7-5XA'| '82A'   | 'IND SMD 150NH 15% 82A(PGL6303.151HLT)'    | 'PLE'   | 'PGL6303.151HLT'       | 'EP(V1)'     | ''        | 'DISCRETE' | ''      | 'S6X-KIMI'    | 'PLE_PGL6303.151HLT.pdf'       | ''                | ''                | ''     | ''         | ''         | '20201026'
 '150NH'               | 'SMLF'    | 'IND'    | 'CV+15^0EZ11'(!)  = ''              | ''             | 'CV+15^0EZ11'     |'L_VLBC12060120R10LF3_12X6XA'| '84A'   | 'IND SMD 150NH 15% 84A(TLM1212Q-151QL)'    | 'DTA'   | 'TLM1212Q-151QL'       | 'EP(V1)'     | ''        | 'DISCRETE' | ''      | 'S8Z-BRIAN'   | 'DTA_TLM1212Q-151QL.pdf'       | ''                | ''                | ''     | ''         | ''         | '20201109'
 '150NH'               | 'SMLF'    | 'EMPTY'  | 'CV+15^0EZ11'(!)  = ''              | ''             | 'CV+15^0EZ11'     |'L_VLBC12060120R10LF3_12X6XA'| '84A'   | 'IND SMD 150NH 15% 84A(TLM1212Q-151QL)'    | 'DTA'   | 'TLM1212Q-151QL'       | 'EP(V1)'     | ''        | 'DISCRETE' | ''      | 'S8Z-BRIAN'   | 'DTA_TLM1212Q-151QL.pdf'       | ''                | ''                | ''     | ''         | ''         | '20201109'
 '150NH'               | 'SMLF'    | 'IND'    | 'CV+15^0EZ07'(!)  = ''              | ''             | 'CV+15^0EZ07'     |'L_VLBC12060120R10LF3_12X6XA'| '82A'   | 'IND SMD 150NH 15% 82A(VLBUC12060120R15LF' | 'TDK'   | 'VLBUC12060120R15LF3N' | 'EP(V1)'     | ''        | 'DISCRETE' | ''      | 'S8Z-BRIAN'   | 'TDK_VLBUC12060120R15LF3N.pdf' | ''                | ''                | ''     | ''         | ''         | '20210302'
 '150NH'               | 'SMLF'    | 'EMPTY'  | 'CV+15^0EZ07'(!)  = ''              | ''             | 'CV+15^0EZ07'     |'L_VLBC12060120R10LF3_12X6XA'| '82A'   | 'IND SMD 150NH 15% 82A(VLBUC12060120R15LF' | 'TDK'   | 'VLBUC12060120R15LF3N' | 'EP(V1)'     | ''        | 'DISCRETE' | ''      | 'S8Z-BRIAN'   | 'TDK_VLBUC12060120R15LF3N.pdf' | ''                | ''                | ''     | ''         | ''         | '20210302'
 '130NH'               | 'SMLF'    | 'IND'    | 'CV+13^0EZ01'(!)  = ''              | ''             | 'CV+13^0EZ01'     |'L_TLM117513Q-151QL_11X7-5XA'| '98A'   | 'IND SMD 130NH 15% 98A(PGL6303.131HLT)'    | 'PLE'   | 'PGL6303.131HLT'       | 'EP(V1)'     | ''        | 'DISCRETE' | ''      | 'S6Q-KIMI'    | 'PLE_PGL6303.131HLT.pdf'       | ''                | ''                | ''     | ''         | ''         | '20210427'
 '130NH'               | 'SMLF'    | 'EMPTY'  | 'CV+13^0EZ01'(!)  = ''              | ''             | 'CV+13^0EZ01'     |'L_TLM117513Q-151QL_11X7-5XA'| '98A'   | 'IND SMD 130NH 15% 98A(PGL6303.131HLT)'    | 'PLE'   | 'PGL6303.131HLT'       | 'EP(V1)'     | ''        | 'DISCRETE' | ''      | 'S6Q-KIMI'    | 'PLE_PGL6303.131HLT.pdf'       | ''                | ''                | ''     | ''         | ''         | '20210427'
 '150NH'               | 'SMLF'    | 'IND'    | 'CV+15^0EZ12'(!)  = ''              | ''             | 'CV+15^0EZ12'     |'L_VLBC12060120R10LF3_12X6XA'| '82A'   | 'IND SMD 150NH 15% 82A(VLBUC12060120R15LF' | 'TDK'   | 'VLBUC12060120R15LF3G' | 'EP(V1)'     | ''        | 'DISCRETE' | ''      | 'S8ZE-CARLOS' | 'TDK_VLBUC12060120R15LF3G.pdf' | ''                | ''                | ''     | ''         | ''         | '20230105'
 '150NH'               | 'SMLF'    | 'EMPTY'  | 'CV+15^0EZ12'(!)  = ''              | ''             | 'CV+15^0EZ12'     |'L_VLBC12060120R10LF3_12X6XA'| '82A'   | 'IND SMD 150NH 15% 82A(VLBUC12060120R15LF' | 'TDK'   | 'VLBUC12060120R15LF3G' | 'EP(V1)'     | ''        | 'DISCRETE' | ''      | 'S8ZE-CARLOS' | 'TDK_VLBUC12060120R15LF3G.pdf' | ''                | ''                | ''     | ''         | ''         | '20230105'
 '150NH'               | 'SMLF'    | 'IND'    | 'CV+15^0EZ11SEL1'(!) = ''              | ''             | 'CV+15^0EZ11SEL1' |'L_VLBC12060120R10LF3_12X6XA'| '84A'   | 'IND SMD 150NH 15% 84A(TLM1212Q SELASN'    | 'DTA'   | 'TLM1212Q-151QL'       | 'EP(V1)'     | ''        | 'DISCRETE' | ''      | 'S8Z-BRIAN'   | 'DTA_TLM1212Q-151QL.pdf'       | 'SEL_15QPN.xlsx'  | ''                | ''     | ''         | ''         | '20230626'
 '150NH'               | 'SMLF'    | 'EMPTY'  | 'CV+15^0EZ11SEL1'(!) = ''              | ''             | 'CV+15^0EZ11SEL1' |'L_VLBC12060120R10LF3_12X6XA'| '84A'   | 'IND SMD 150NH 15% 84A(TLM1212Q SELASN'    | 'DTA'   | 'TLM1212Q-151QL'       | 'EP(V1)'     | ''        | 'DISCRETE' | ''      | 'S8Z-BRIAN'   | 'DTA_TLM1212Q-151QL.pdf'       | 'SEL_15QPN.xlsx'  | ''                | ''     | ''         | ''         | '20230626'
 '150NH'               | 'SMLF'    | 'IND'    | 'CV+15^0EZ12SEL1'(!) = ''              | ''             | 'CV+15^0EZ12SEL1' |'L_VLBC12060120R10LF3_12X6XA'| '82A'   | 'IND SMD 150NH 15% 82A(VLBUC1206012)SELA'  | 'TDK'   | 'VLBUC12060120R15LF3G' | 'EP(V1)'     | ''        | 'DISCRETE' | ''      | 'S8ZE-CARLOS' | 'TDK_VLBUC12060120R15LF3G.pdf' | 'SEL_15QPN.xlsx'  | ''                | ''     | ''         | ''         | '20230626'
 '150NH'               | 'SMLF'    | 'EMPTY'  | 'CV+15^0EZ12SEL1'(!) = ''              | ''             | 'CV+15^0EZ12SEL1' |'L_VLBC12060120R10LF3_12X6XA'| '82A'   | 'IND SMD 150NH 15% 82A(VLBUC1206012)SELA'  | 'TDK'   | 'VLBUC12060120R15LF3G' | 'EP(V1)'     | ''        | 'DISCRETE' | ''      | 'S8ZE-CARLOS' | 'TDK_VLBUC12060120R15LF3G.pdf' | 'SEL_15QPN.xlsx'  | ''                | ''     | ''         | ''         | '20230626'
 '150NH'               | 'SMLF'    | 'IND'    | 'CV+15^0EZ19'(!)  = ''              | ''             | 'CV+15^0EZ19'     |'L_4S_PAL6374_10X5'| '71A'   | 'IND SMD 150NH 15% 71A(PAL6374.151HLT)'    | 'YGO'   | 'PAL6374.151HLT'       | 'EP(V1)'     | ''        | 'DISCRETE' | ''      | 'F0M-GREG'    | 'YGO_PAL6374.151HLT.pdf'       | ''                | ''                | ''     | ''         | ''         | '20230720'
 '150NH'               | 'SMLF'    | 'EMPTY'  | 'CV+15^0EZ19'(!)  = ''              | ''             | 'CV+15^0EZ19'     |'L_4S_PAL6374_10X5'| '71A'   | 'IND SMD 150NH 15% 71A(PAL6374.151HLT)'    | 'YGO'   | 'PAL6374.151HLT'       | 'EP(V1)'     | ''        | 'DISCRETE' | ''      | 'F0M-GREG'    | 'YGO_PAL6374.151HLT.pdf'       | ''                | ''                | ''     | ''         | ''         | '20230720'
 '120NH'               | 'SMLF'    | 'IND'    | 'CV+12^0EZ06'(!)  = ''               | ''               | 'CV+12^0EZ06'     |'L_TLM117513Q-151QL_11X7-5XA'| '106A'  | 'IND SMD 120NH 15% 106(PGL6303.121HLT)'    | 'PLE'   | 'PGL6303.121HLT'       | 'EP(V1)'     | ''        | 'DISCRETE' | ''      | 'S9B-NINA'    | 'PLE_PGL6303.121HLT.pdf'       | ''                | ''                | ''     | ''         | ''         | '20230809'
 '120NH'               | 'SMLF'    | 'EMPTY'  | 'CV+12^0EZ06'(!)  = ''               | ''               | 'CV+12^0EZ06'     |'L_TLM117513Q-151QL_11X7-5XA'| '106A'  | 'IND SMD 120NH 15% 106(PGL6303.121HLT)'    | 'PLE'   | 'PGL6303.121HLT'       | 'EP(V1)'     | ''        | 'DISCRETE' | ''      | 'S9B-NINA'    | 'PLE_PGL6303.121HLT.pdf'       | ''                | ''                | ''     | ''         | ''         | '20230809'

END_PART

END.

